# BASEBOARD_FAB2 (Tioga Pass) — schematic netlist excerpt (pin names and nets, part order shuffled) for the footprints in the layout excerpt that follows; sources: Cadence DE-HDL packaged netlist, KiCad conversion of Wiwynn_Tioga_Pass_MB.brd

C3A3  CAP  10UF 4V 20% X6S  pkg 0603LF  page 234 : A = PVPP_KLM ; B = GND
C2D3  CAP_A  22.0UF 4V 20% X6S  pkg 0603V  page 228 : A = PVDDQ_KLM ; B = GND
C1C1  CAPP  270UF 16V 20% OSCON  pkg 2626  page 209 : A = VR_FET_SW_P12V_STBY_PVCCIN_CPU1 ; B = GND

(kicad_pcb
	(version 20260206)
	(generator "pcbnew")
	(generator_version "10.0")
	(general
		(thickness 1.6)
		(legacy_teardrops no)
	)
	(paper "A4")
	(title_block
		(title "Wiwynn_Tioga_Pass_MB.brd")
		(comment 1 "Tioga Pass / footprints 92-94 of 4770")
	)
	(layers
		(0 "F.Cu" signal "TOP")
		(4 "In1.Cu" signal "L2GND")
		(6 "In2.Cu" signal "L3")
		(8 "In3.Cu" signal "L4GND")
		(10 "In4.Cu" signal "L5")
		(12 "In5.Cu" signal "L6GND")
		(14 "In6.Cu" signal "L7VCC")
		(16 "In7.Cu" signal "L8VCC")
		(18 "In8.Cu" signal "L9GND")
		(20 "In9.Cu" signal "L10")
		(22 "In10.Cu" signal "L11GND")
		(24 "In11.Cu" signal "L12")
		(26 "In12.Cu" signal "L13GND")
		(2 "B.Cu" signal "BOTTOM")
		(9 "F.Adhes" user "F.Adhesive")
		(11 "B.Adhes" user "B.Adhesive")
		(13 "F.Paste" user "Package Geometry/Pastemask Top")
		(15 "B.Paste" user "Package Geometry/Pastemask Bottom")
		(5 "F.SilkS" user "Ref Des/Silkscreen Top")
		(7 "B.SilkS" user "Ref Des/Silkscreen Bottom")
		(1 "F.Mask" user "Board Geometry/Soldermask Top")
		(3 "B.Mask" user "Board Geometry/Soldermask Bottom")
		(17 "Dwgs.User" user "User.Drawings")
		(19 "Cmts.User" user "User.Comments")
		(21 "Eco1.User" user "User.Eco1")
		(23 "Eco2.User" user "User.Eco2")
		(25 "Edge.Cuts" user "Board Geometry/Outline")
		(27 "Margin" user)
		(31 "F.CrtYd" user "Package Geometry/Place Bound Top")
		(29 "B.CrtYd" user "Package Geometry/Place Bound Bottom")
		(35 "F.Fab" user "Ref Des/Assembly Top")
		(33 "B.Fab" user "Ref Des/Assembly Bottom")
	)
	(footprint ""
		(layer "F.Cu")
		(at 105.995978 -84.890102)
		(property "Reference" "C2D3"
			(at 0 0 0)
			(layer "F.SilkS")
			(hide yes)
			(effects
				(font
					(size 1.27 1.27)
				)
			)
		)
		(property "Value" ""
			(at 0 0 0)
			(layer "F.Fab")
			(effects
				(font
					(size 1.27 1.27)
				)
			)
		)
		(duplicate_pad_numbers_are_jumpers no)
		(fp_poly
			(pts
				(xy -0.4953 -0.2032) (xy 0.4953 -0.2032) (xy 0.4953 1.6002) (xy -0.4953 1.6002)
			)
			(stroke
				(width 0)
				(type default)
			)
			(fill no)
			(layer "F.CrtYd")
		)
		(fp_line
			(start -0.4953 -0.2032)
			(end 0.4953 -0.2032)
			(stroke
				(width 0.1)
				(type default)
			)
			(layer "F.Fab")
		)
		(fp_line
			(start -0.4953 1.6002)
			(end -0.4953 -0.2032)
			(stroke
				(width 0.1)
				(type default)
			)
			(layer "F.Fab")
		)
		(fp_line
			(start 0.4953 -0.2032)
			(end 0.4953 1.6002)
			(stroke
				(width 0.1)
				(type default)
			)
			(layer "F.Fab")
		)
		(fp_line
			(start 0.4953 1.6002)
			(end -0.4953 1.6002)
			(stroke
				(width 0.1)
				(type default)
			)
			(layer "F.Fab")
		)
		(pad "1" smd rect
			(at 0 0)
			(size 0.762 0.889)
			(layers "F.Cu" "F.Mask" "F.Paste")
			(net "PVDDQ_KLM")
		)
		(pad "2" smd rect
			(at 0 1.397)
			(size 0.762 0.889)
			(layers "F.Cu" "F.Mask" "F.Paste")
			(net "GND")
		)
		(zone
			(layer "F.Cu")
			(hatch none 0.5)
			(connect_pads
				(clearance 0)
			)
			(min_thickness 0.25)
			(keepout
				(tracks not_allowed)
				(vias allowed)
				(pads allowed)
				(copperpour not_allowed)
				(footprints allowed)
			)
			(placement
				(enabled no)
				(sheetname "")
			)
			(fill
				(thermal_gap 0.5)
				(thermal_bridge_width 0.5)
				(island_removal_mode 0)
			)
			(polygon
				(pts
					(xy 105.614978 -84.445602) (xy 106.376978 -84.445602) (xy 106.376978 -83.937602) (xy 105.614978 -83.937602)
				)
			)
		)
	)
	(footprint ""
		(layer "F.Cu")
		(at 25.520142 -109.542834 -90)
		(property "Reference" "C1C1"
			(at 1.397 -2.69367 90)
			(unlocked yes)
			(layer "F.SilkS")
			(effects
				(font
					(size 0.7874 0.5842)
					(thickness 0.1524)
				)
				(justify left)
			)
		)
		(property "Value" ""
			(at 0 0 270)
			(layer "F.Fab")
			(effects
				(font
					(size 1.27 1.27)
				)
			)
		)
		(duplicate_pad_numbers_are_jumpers no)
		(fp_line
			(start -3.400044 6.067044)
			(end -0.9017 6.067044)
			(stroke
				(width 0.1524)
				(type default)
			)
			(layer "F.SilkS")
		)
		(fp_line
			(start 0.9017 6.067044)
			(end 3.400044 6.067044)
			(stroke
				(width 0.1524)
				(type default)
			)
			(layer "F.SilkS")
		)
		(fp_line
			(start 3.400044 6.067044)
			(end 3.400044 0.028956)
			(stroke
				(width 0.1524)
				(type default)
			)
			(layer "F.SilkS")
		)
		(fp_line
			(start -0.9017 1.587754)
			(end -0.7239 1.587754)
			(stroke
				(width 0.1524)
				(type default)
			)
			(layer "F.SilkS")
		)
		(fp_line
			(start 0.7239 1.587754)
			(end 0.9017 1.587754)
			(stroke
				(width 0.1524)
				(type default)
			)
			(layer "F.SilkS")
		)
		(fp_line
			(start 0.9017 1.587754)
			(end 0.9017 -1.714246)
			(stroke
				(width 0.1524)
				(type default)
			)
			(layer "F.SilkS")
		)
		(fp_line
			(start -3.400044 0.028956)
			(end -3.400044 6.067044)
			(stroke
				(width 0.1524)
				(type default)
			)
			(layer "F.SilkS")
		)
		(fp_line
			(start 3.400044 0.028956)
			(end 2.638044 -0.733044)
			(stroke
				(width 0.1524)
				(type default)
			)
			(layer "F.SilkS")
		)
		(fp_line
			(start -2.638044 -0.733044)
			(end -3.400044 0.028956)
			(stroke
				(width 0.1524)
				(type default)
			)
			(layer "F.SilkS")
		)
		(fp_line
			(start -0.9017 -0.733044)
			(end -2.638044 -0.733044)
			(stroke
				(width 0.1524)
				(type default)
			)
			(layer "F.SilkS")
		)
		(fp_line
			(start 2.638044 -0.733044)
			(end 0.9017 -0.733044)
			(stroke
				(width 0.1524)
				(type default)
			)
			(layer "F.SilkS")
		)
		(fp_line
			(start -0.9017 -1.714246)
			(end -0.9017 1.587754)
			(stroke
				(width 0.1524)
				(type default)
			)
			(layer "F.SilkS")
		)
		(fp_line
			(start -0.7239 -1.714246)
			(end -0.9017 -1.714246)
			(stroke
				(width 0.1524)
				(type default)
			)
			(layer "F.SilkS")
		)
		(fp_line
			(start 0.9017 -1.714246)
			(end 0.7239 -1.714246)
			(stroke
				(width 0.1524)
				(type default)
			)
			(layer "F.SilkS")
		)
		(fp_poly
			(pts
				(xy -3.400044 6.067044) (xy 3.400044 6.067044) (xy 3.400044 0.028956) (xy 2.638044 -0.733044) (xy -2.638044 -0.733044)
				(xy -3.400044 0.028956)
			)
			(stroke
				(width 0)
				(type default)
			)
			(fill no)
			(layer "F.CrtYd")
		)
		(fp_line
			(start -3.400044 6.067044)
			(end 3.400044 6.067044)
			(stroke
				(width 0.1)
				(type default)
			)
			(layer "F.Fab")
		)
		(fp_line
			(start 3.400044 6.067044)
			(end 3.400044 0.028956)
			(stroke
				(width 0.1)
				(type default)
			)
			(layer "F.Fab")
		)
		(fp_line
			(start -3.400044 0.028956)
			(end -3.400044 6.067044)
			(stroke
				(width 0.1)
				(type default)
			)
			(layer "F.Fab")
		)
		(fp_line
			(start 3.400044 0.028956)
			(end 2.638044 -0.733044)
			(stroke
				(width 0.1)
				(type default)
			)
			(layer "F.Fab")
		)
		(fp_line
			(start -2.638044 -0.733044)
			(end -3.400044 0.028956)
			(stroke
				(width 0.1)
				(type default)
			)
			(layer "F.Fab")
		)
		(fp_line
			(start 2.638044 -0.733044)
			(end -2.638044 -0.733044)
			(stroke
				(width 0.1)
				(type default)
			)
			(layer "F.Fab")
		)
		(fp_circle
			(center 0 2.667)
			(end 0 -0.733044)
			(stroke
				(width 0.1)
				(type default)
			)
			(fill no)
			(layer "F.Fab")
		)
		(pad "1" smd rect
			(at 0 0 270)
			(size 0.7874 3.429)
			(layers "F.Cu" "F.Mask" "F.Paste")
			(net "VR_FET_SW_P12V_STBY_PVCCIN_CPU1")
		)
		(pad "2" smd rect
			(at 0 5.334 270)
			(size 0.7874 3.429)
			(layers "F.Cu" "F.Mask" "F.Paste")
			(net "GND")
		)
	)
	(footprint ""
		(layer "F.Cu")
		(at 153.4922 -149.606 -90)
		(property "Reference" "C3A3"
			(at 0 0 270)
			(layer "F.SilkS")
			(hide yes)
			(effects
				(font
					(size 1.27 1.27)
				)
			)
		)
		(property "Value" ""
			(at 0 0 270)
			(layer "F.Fab")
			(effects
				(font
					(size 1.27 1.27)
				)
			)
		)
		(duplicate_pad_numbers_are_jumpers no)
		(fp_rect
			(start -0.4953 1.6002)
			(end 0.4953 -0.2032)
			(stroke
				(width 0)
				(type default)
			)
			(fill no)
			(layer "F.CrtYd")
		)
		(fp_line
			(start -0.4953 1.6002)
			(end -0.4953 -0.2032)
			(stroke
				(width 0.1)
				(type default)
			)
			(layer "F.Fab")
		)
		(fp_line
			(start 0.4953 1.6002)
			(end -0.4953 1.6002)
			(stroke
				(width 0.1)
				(type default)
			)
			(layer "F.Fab")
		)
		(fp_line
			(start -0.4953 -0.2032)
			(end 0.4953 -0.2032)
			(stroke
				(width 0.1)
				(type default)
			)
			(layer "F.Fab")
		)
		(fp_line
			(start 0.4953 -0.2032)
			(end 0.4953 1.6002)
			(stroke
				(width 0.1)
				(type default)
			)
			(layer "F.Fab")
		)
		(pad "1" smd rect
			(at 0 0 270)
			(size 0.762 0.889)
			(layers "F.Cu" "F.Mask" "F.Paste")
			(net "PVPP_KLM")
		)
		(pad "2" smd rect
			(at 0 1.397 270)
			(size 0.762 0.889)
			(layers "F.Cu" "F.Mask" "F.Paste")
			(net "GND")
		)
		(zone
			(layer "F.Cu")
			(hatch none 0.5)
			(connect_pads
				(clearance 0)
			)
			(min_thickness 0.25)
			(keepout
				(tracks not_allowed)
				(vias allowed)
				(pads allowed)
				(copperpour not_allowed)
				(footprints allowed)
			)
			(placement
				(enabled no)
				(sheetname "")
			)
			(fill
				(thermal_gap 0.5)
				(thermal_bridge_width 0.5)
				(island_removal_mode 0)
			)
			(polygon
				(pts
					(xy 152.5397 -149.987) (xy 152.5397 -149.225) (xy 153.0477 -149.225) (xy 153.0477 -149.987)
				)
			)
		)
	)
)
